(kicad_pcb
	(version 20260206)
	(generator "pcbnew")
	(generator_version "10.0")
	(general
		(thickness 1.6)
		(legacy_teardrops no)
	)
	(paper "A4")
	(title_block
		(title "v1-chassis-manager — T6M_CM_d_v01_1031_1645.brd")
		(comment 1 "Open CloudServer (Microsoft) / footprints 43-52 of 2512")
	)
	(layers
		(0 "F.Cu" signal "TOP")
		(4 "In1.Cu" signal "GND1")
		(6 "In2.Cu" signal "IN1")
		(8 "In3.Cu" signal "VCC1")
		(10 "In4.Cu" signal "VCC2")
		(12 "In5.Cu" signal "GND2")
		(14 "In6.Cu" signal "IN2")
		(16 "In7.Cu" signal "IN3")
		(18 "In8.Cu" signal "GND3")
		(2 "B.Cu" signal "BOTTOM")
		(9 "F.Adhes" user "F.Adhesive")
		(11 "B.Adhes" user "B.Adhesive")
		(13 "F.Paste" user "Package Geometry/Pastemask Top")
		(15 "B.Paste" user "Package Geometry/Pastemask Bottom")
		(5 "F.SilkS" user "Ref Des/Silkscreen Top")
		(7 "B.SilkS" user "Ref Des/Silkscreen Bottom")
		(1 "F.Mask" user "Board Geometry/Soldermask Top")
		(3 "B.Mask" user "Board Geometry/Soldermask Bottom")
		(17 "Dwgs.User" user "User.Drawings")
		(19 "Cmts.User" user "User.Comments")
		(21 "Eco1.User" user "User.Eco1")
		(23 "Eco2.User" user "User.Eco2")
		(25 "Edge.Cuts" user "Board Geometry/Outline")
		(27 "Margin" user)
		(31 "F.CrtYd" user "Package Geometry/Place Bound Top")
		(29 "B.CrtYd" user "Package Geometry/Place Bound Bottom")
		(35 "F.Fab" user "Ref Des/Assembly Top")
		(33 "B.Fab" user "Ref Des/Assembly Bottom")
	)
	(footprint ""
		(layer "F.Cu")
		(at 117.20576 -175.426624 90)
		(property "Reference" "R805"
			(at -57.046622 32.819848 90)
			(unlocked yes)
			(layer "F.SilkS")
			(effects
				(font
					(size 0.7874 0.5842)
					(thickness 0.1524)
				)
				(justify left)
			)
		)
		(property "Value" ""
			(at 0 0 90)
			(layer "F.Fab")
			(effects
				(font
					(size 1.27 1.27)
				)
			)
		)
		(duplicate_pad_numbers_are_jumpers no)
		(fp_line
			(start 0.7874 -0.4064)
			(end 0.7874 0.4064)
			(stroke
				(width 0.1524)
				(type default)
			)
			(layer "F.SilkS")
		)
		(fp_line
			(start -0.7874 -0.4064)
			(end 0.7874 -0.4064)
			(stroke
				(width 0.1524)
				(type default)
			)
			(layer "F.SilkS")
		)
		(fp_line
			(start 0.7874 0.4064)
			(end -0.7874 0.4064)
			(stroke
				(width 0.1524)
				(type default)
			)
			(layer "F.SilkS")
		)
		(fp_line
			(start -0.7874 0.4064)
			(end -0.7874 -0.4064)
			(stroke
				(width 0.1524)
				(type default)
			)
			(layer "F.SilkS")
		)
		(fp_poly
			(pts
				(xy -0.508 0.2794) (xy -0.508 0.2286) (xy -0.635 0.2286) (xy -0.635 -0.254) (xy -0.5334 -0.254)
				(xy -0.5334 -0.2794) (xy 0.5334 -0.2794) (xy 0.5334 -0.254) (xy 0.635 -0.254) (xy 0.635 0.254) (xy 0.5334 0.254)
				(xy 0.5334 0.2794)
			)
			(stroke
				(width 0)
				(type default)
			)
			(fill no)
			(layer "F.CrtYd")
		)
		(pad "1" smd rect
			(at 0.40005 0 90)
			(size 0.4572 0.508)
			(layers "F.Cu" "F.Mask" "F.Paste")
			(net "N31341803")
		)
		(pad "2" smd rect
			(at -0.40005 0 90)
			(size 0.4572 0.508)
			(layers "F.Cu" "F.Mask" "F.Paste")
			(net "GND")
		)
	)
	(footprint ""
		(layer "F.Cu")
		(at 122.893328 -158.608014 180)
		(property "Reference" "U118"
			(at 59.338718 -109.210348 90)
			(unlocked yes)
			(layer "F.SilkS")
			(effects
				(font
					(size 0.7874 0.5842)
					(thickness 0.1524)
				)
			)
		)
		(property "Value" ""
			(at 0 0 180)
			(layer "F.Fab")
			(effects
				(font
					(size 1.27 1.27)
				)
			)
		)
		(duplicate_pad_numbers_are_jumpers no)
		(fp_line
			(start 1.651 1.905)
			(end -1.651 1.905)
			(stroke
				(width 0.1524)
				(type default)
			)
			(layer "F.SilkS")
		)
		(fp_line
			(start 1.651 -1.905)
			(end 1.651 1.905)
			(stroke
				(width 0.1524)
				(type default)
			)
			(layer "F.SilkS")
		)
		(fp_line
			(start -1.651 1.905)
			(end -1.651 -1.905)
			(stroke
				(width 0.1524)
				(type default)
			)
			(layer "F.SilkS")
		)
		(fp_line
			(start -1.651 -1.905)
			(end 1.651 -1.905)
			(stroke
				(width 0.1524)
				(type default)
			)
			(layer "F.SilkS")
		)
		(fp_poly
			(pts
				(xy -1.524 0.7112) (xy -1.524 1.7526) (xy -0.508 1.7526) (xy -0.508 0.6985) (xy 0.508 0.6985) (xy 0.508 1.7526)
				(xy 1.524 1.7526) (xy 1.524 0.6985) (xy 1.524 -0.6985) (xy 0.508 -0.6985) (xy 0.508 -1.7526) (xy -0.508 -1.7526)
				(xy -0.508 -0.6985) (xy -1.524 -0.6985) (xy -1.524 0.6985)
			)
			(stroke
				(width 0)
				(type default)
			)
			(fill no)
			(layer "F.CrtYd")
		)
		(fp_text user "S"
			(at 1.938528 1.316736 0)
			(unlocked yes)
			(layer "F.SilkS")
			(effects
				(font
					(size 0.635 0.4064)
					(thickness 0.1524)
				)
			)
		)
		(fp_text user "G"
			(at -0.093472 1.189736 0)
			(unlocked yes)
			(layer "F.SilkS")
			(effects
				(font
					(size 0.635 0.4064)
					(thickness 0.1524)
				)
			)
		)
		(fp_text user "D"
			(at -1.12141 -1.356614 0)
			(unlocked yes)
			(layer "F.SilkS")
			(effects
				(font
					(size 0.635 0.4064)
					(thickness 0.1524)
				)
			)
		)
		(pad "D" smd rect
			(at 0 -1.1176 180)
			(size 1.016 1.27)
			(layers "F.Cu" "F.Mask" "F.Paste")
			(net "I2C_PSU2_SDA")
		)
		(pad "G" smd rect
			(at -1.016 1.1176 180)
			(size 1.016 1.27)
			(layers "F.Cu" "F.Mask" "F.Paste")
			(net "PMBUS2_EN")
		)
		(pad "S" smd rect
			(at 1.016 1.1176 180)
			(size 1.016 1.27)
			(layers "F.Cu" "F.Mask" "F.Paste")
			(net "I2C_PSU2_SDA_MOS")
		)
	)
	(footprint ""
		(layer "F.Cu")
		(at 66.41338 -170.630088)
		(property "Reference" "C617"
			(at -10.195306 131.070096 0)
			(unlocked yes)
			(layer "F.SilkS")
			(effects
				(font
					(size 0.7874 0.5842)
					(thickness 0.1524)
				)
				(justify left)
			)
		)
		(property "Value" ""
			(at 0 0 0)
			(layer "F.Fab")
			(effects
				(font
					(size 1.27 1.27)
				)
			)
		)
		(duplicate_pad_numbers_are_jumpers no)
		(fp_line
			(start -0.7874 -0.4064)
			(end 0.7874 -0.4064)
			(stroke
				(width 0.1524)
				(type default)
			)
			(layer "F.SilkS")
		)
		(fp_line
			(start -0.7874 0.4064)
			(end -0.7874 -0.4064)
			(stroke
				(width 0.1524)
				(type default)
			)
			(layer "F.SilkS")
		)
		(fp_line
			(start 0 0.381)
			(end 0 -0.381)
			(stroke
				(width 0.1524)
				(type default)
			)
			(layer "F.SilkS")
		)
		(fp_line
			(start 0.7874 -0.4064)
			(end 0.7874 0.4064)
			(stroke
				(width 0.1524)
				(type default)
			)
			(layer "F.SilkS")
		)
		(fp_line
			(start 0.7874 0.4064)
			(end -0.7874 0.4064)
			(stroke
				(width 0.1524)
				(type default)
			)
			(layer "F.SilkS")
		)
		(fp_poly
			(pts
				(xy -0.5334 0.254) (xy -0.635 0.254) (xy -0.635 0.2286) (xy -0.635 -0.254) (xy -0.5334 -0.254) (xy -0.5334 -0.2794)
				(xy 0.5334 -0.2794) (xy 0.5334 -0.254) (xy 0.635 -0.254) (xy 0.635 0.254) (xy 0.5334 0.254) (xy 0.5334 0.2794)
				(xy -0.508 0.2794) (xy -0.5334 0.2794)
			)
			(stroke
				(width 0)
				(type default)
			)
			(fill no)
			(layer "F.CrtYd")
		)
		(pad "1" smd rect
			(at 0.40005 0)
			(size 0.4572 0.508)
			(layers "F.Cu" "F.Mask" "F.Paste")
			(net "P3V3_NODE1")
		)
		(pad "2" smd rect
			(at -0.40005 0)
			(size 0.4572 0.508)
			(layers "F.Cu" "F.Mask" "F.Paste")
			(net "GND")
		)
	)
	(footprint ""
		(layer "F.Cu")
		(at 92.819982 -137.581894 90)
		(property "Reference" "C816"
			(at 1.288542 -0.084328 90)
			(unlocked yes)
			(layer "F.SilkS")
			(effects
				(font
					(size 0.7874 0.5842)
					(thickness 0.1524)
				)
				(justify left)
			)
		)
		(property "Value" ""
			(at 0 0 90)
			(layer "F.Fab")
			(effects
				(font
					(size 1.27 1.27)
				)
			)
		)
		(duplicate_pad_numbers_are_jumpers no)
		(fp_line
			(start 0.7874 -0.4064)
			(end 0.7874 0.4064)
			(stroke
				(width 0.1524)
				(type default)
			)
			(layer "F.SilkS")
		)
		(fp_line
			(start -0.7874 -0.4064)
			(end 0.7874 -0.4064)
			(stroke
				(width 0.1524)
				(type default)
			)
			(layer "F.SilkS")
		)
		(fp_line
			(start 0 0.381)
			(end 0 -0.381)
			(stroke
				(width 0.1524)
				(type default)
			)
			(layer "F.SilkS")
		)
		(fp_line
			(start 0.7874 0.4064)
			(end -0.7874 0.4064)
			(stroke
				(width 0.1524)
				(type default)
			)
			(layer "F.SilkS")
		)
		(fp_line
			(start -0.7874 0.4064)
			(end -0.7874 -0.4064)
			(stroke
				(width 0.1524)
				(type default)
			)
			(layer "F.SilkS")
		)
		(fp_poly
			(pts
				(xy -0.5334 0.254) (xy -0.635 0.254) (xy -0.635 0.2286) (xy -0.635 -0.254) (xy -0.5334 -0.254) (xy -0.5334 -0.2794)
				(xy 0.5334 -0.2794) (xy 0.5334 -0.254) (xy 0.635 -0.254) (xy 0.635 0.254) (xy 0.5334 0.254) (xy 0.5334 0.2794)
				(xy -0.508 0.2794) (xy -0.5334 0.2794)
			)
			(stroke
				(width 0)
				(type default)
			)
			(fill no)
			(layer "F.CrtYd")
		)
		(pad "1" smd rect
			(at 0.40005 0 90)
			(size 0.4572 0.508)
			(layers "F.Cu" "F.Mask" "F.Paste")
			(net "GND")
		)
		(pad "2" smd rect
			(at -0.40005 0 90)
			(size 0.4572 0.508)
			(layers "F.Cu" "F.Mask" "F.Paste")
			(net "PWRGD_NODE1_P1V05_SUS_PG")
		)
	)
	(footprint ""
		(layer "F.Cu")
		(at 142.75816 -117.082824 180)
		(property "Reference" "R12"
			(at -1.487424 -0.09906 0)
			(unlocked yes)
			(layer "F.SilkS")
			(effects
				(font
					(size 0.7874 0.5842)
					(thickness 0.1524)
				)
				(justify left)
			)
		)
		(property "Value" ""
			(at 0 0 180)
			(layer "F.Fab")
			(effects
				(font
					(size 1.27 1.27)
				)
			)
		)
		(duplicate_pad_numbers_are_jumpers no)
		(fp_line
			(start 0.7874 0.4064)
			(end -0.7874 0.4064)
			(stroke
				(width 0.1524)
				(type default)
			)
			(layer "F.SilkS")
		)
		(fp_line
			(start 0.7874 -0.4064)
			(end 0.7874 0.4064)
			(stroke
				(width 0.1524)
				(type default)
			)
			(layer "F.SilkS")
		)
		(fp_line
			(start -0.7874 0.4064)
			(end -0.7874 -0.4064)
			(stroke
				(width 0.1524)
				(type default)
			)
			(layer "F.SilkS")
		)
		(fp_line
			(start -0.7874 -0.4064)
			(end 0.7874 -0.4064)
			(stroke
				(width 0.1524)
				(type default)
			)
			(layer "F.SilkS")
		)
		(fp_poly
			(pts
				(xy -0.508 0.2794) (xy -0.508 0.2286) (xy -0.635 0.2286) (xy -0.635 -0.254) (xy -0.5334 -0.254)
				(xy -0.5334 -0.2794) (xy 0.5334 -0.2794) (xy 0.5334 -0.254) (xy 0.635 -0.254) (xy 0.635 0.254) (xy 0.5334 0.254)
				(xy 0.5334 0.2794)
			)
			(stroke
				(width 0)
				(type default)
			)
			(fill no)
			(layer "F.CrtYd")
		)
		(pad "1" smd rect
			(at 0.40005 0 180)
			(size 0.4572 0.508)
			(layers "F.Cu" "F.Mask" "F.Paste")
			(net "SEL_PCI_27M")
		)
		(pad "2" smd rect
			(at -0.40005 0 180)
			(size 0.4572 0.508)
			(layers "F.Cu" "F.Mask" "F.Paste")
			(net "P3V3_CLK_NODE1")
		)
	)
	(footprint ""
		(layer "F.Cu")
		(at 63.832486 -118.783862 90)
		(property "Reference" "R326"
			(at -5.013706 -0.666242 90)
			(unlocked yes)
			(layer "F.SilkS")
			(effects
				(font
					(size 0.7874 0.5842)
					(thickness 0.1524)
				)
				(justify left)
			)
		)
		(property "Value" ""
			(at 0 0 90)
			(layer "F.Fab")
			(effects
				(font
					(size 1.27 1.27)
				)
			)
		)
		(duplicate_pad_numbers_are_jumpers no)
		(fp_line
			(start 0.7874 -0.4064)
			(end 0.7874 0.4064)
			(stroke
				(width 0.1524)
				(type default)
			)
			(layer "F.SilkS")
		)
		(fp_line
			(start -0.7874 -0.4064)
			(end 0.7874 -0.4064)
			(stroke
				(width 0.1524)
				(type default)
			)
			(layer "F.SilkS")
		)
		(fp_line
			(start 0.7874 0.4064)
			(end -0.7874 0.4064)
			(stroke
				(width 0.1524)
				(type default)
			)
			(layer "F.SilkS")
		)
		(fp_line
			(start -0.7874 0.4064)
			(end -0.7874 -0.4064)
			(stroke
				(width 0.1524)
				(type default)
			)
			(layer "F.SilkS")
		)
		(fp_poly
			(pts
				(xy -0.508 0.2794) (xy -0.508 0.2286) (xy -0.635 0.2286) (xy -0.635 -0.254) (xy -0.5334 -0.254)
				(xy -0.5334 -0.2794) (xy 0.5334 -0.2794) (xy 0.5334 -0.254) (xy 0.635 -0.254) (xy 0.635 0.254) (xy 0.5334 0.254)
				(xy 0.5334 0.2794)
			)
			(stroke
				(width 0)
				(type default)
			)
			(fill no)
			(layer "F.CrtYd")
		)
		(pad "1" smd rect
			(at 0.40005 0 90)
			(size 0.4572 0.508)
			(layers "F.Cu" "F.Mask" "F.Paste")
			(net "P3V3_NODE1")
		)
		(pad "2" smd rect
			(at -0.40005 0 90)
			(size 0.4572 0.508)
			(layers "F.Cu" "F.Mask" "F.Paste")
			(net "BMC_ROMA10")
		)
	)
	(footprint ""
		(layer "F.Cu")
		(at 44.516802 -145.829782 -90)
		(property "Reference" "R546"
			(at 0.88646 6.618732 90)
			(unlocked yes)
			(layer "F.SilkS")
			(effects
				(font
					(size 0.7874 0.5842)
					(thickness 0.1524)
				)
				(justify left)
			)
		)
		(property "Value" ""
			(at 0 0 270)
			(layer "F.Fab")
			(effects
				(font
					(size 1.27 1.27)
				)
			)
		)
		(duplicate_pad_numbers_are_jumpers no)
		(fp_line
			(start -0.7874 0.4064)
			(end -0.7874 -0.4064)
			(stroke
				(width 0.1524)
				(type default)
			)
			(layer "F.SilkS")
		)
		(fp_line
			(start 0.7874 0.4064)
			(end -0.7874 0.4064)
			(stroke
				(width 0.1524)
				(type default)
			)
			(layer "F.SilkS")
		)
		(fp_line
			(start -0.7874 -0.4064)
			(end 0.7874 -0.4064)
			(stroke
				(width 0.1524)
				(type default)
			)
			(layer "F.SilkS")
		)
		(fp_line
			(start 0.7874 -0.4064)
			(end 0.7874 0.4064)
			(stroke
				(width 0.1524)
				(type default)
			)
			(layer "F.SilkS")
		)
		(fp_poly
			(pts
				(xy -0.508 0.2794) (xy -0.508 0.2286) (xy -0.635 0.2286) (xy -0.635 -0.254) (xy -0.5334 -0.254)
				(xy -0.5334 -0.2794) (xy 0.5334 -0.2794) (xy 0.5334 -0.254) (xy 0.635 -0.254) (xy 0.635 0.254) (xy 0.5334 0.254)
				(xy 0.5334 0.2794)
			)
			(stroke
				(width 0)
				(type default)
			)
			(fill no)
			(layer "F.CrtYd")
		)
		(pad "1" smd rect
			(at 0.40005 0 270)
			(size 0.4572 0.508)
			(layers "F.Cu" "F.Mask" "F.Paste")
			(net "P3V3_NODE1")
		)
		(pad "2" smd rect
			(at -0.40005 0 270)
			(size 0.4572 0.508)
			(layers "F.Cu" "F.Mask" "F.Paste")
			(net "LAN1_NC_SI_TDX1")
		)
	)
	(footprint ""
		(layer "F.Cu")
		(at 135.36676 -185.205624 90)
		(property "Reference" "C743"
			(at 4.510786 -0.076708 90)
			(unlocked yes)
			(layer "F.SilkS")
			(effects
				(font
					(size 0.7874 0.5842)
					(thickness 0.1524)
				)
				(justify left)
			)
		)
		(property "Value" ""
			(at 0 0 90)
			(layer "F.Fab")
			(effects
				(font
					(size 1.27 1.27)
				)
			)
		)
		(duplicate_pad_numbers_are_jumpers no)
		(fp_line
			(start 0.7874 -0.4064)
			(end 0.7874 0.4064)
			(stroke
				(width 0.1524)
				(type default)
			)
			(layer "F.SilkS")
		)
		(fp_line
			(start -0.7874 -0.4064)
			(end 0.7874 -0.4064)
			(stroke
				(width 0.1524)
				(type default)
			)
			(layer "F.SilkS")
		)
		(fp_line
			(start 0 0.381)
			(end 0 -0.381)
			(stroke
				(width 0.1524)
				(type default)
			)
			(layer "F.SilkS")
		)
		(fp_line
			(start 0.7874 0.4064)
			(end -0.7874 0.4064)
			(stroke
				(width 0.1524)
				(type default)
			)
			(layer "F.SilkS")
		)
		(fp_line
			(start -0.7874 0.4064)
			(end -0.7874 -0.4064)
			(stroke
				(width 0.1524)
				(type default)
			)
			(layer "F.SilkS")
		)
		(fp_poly
			(pts
				(xy -0.5334 0.254) (xy -0.635 0.254) (xy -0.635 0.2286) (xy -0.635 -0.254) (xy -0.5334 -0.254) (xy -0.5334 -0.2794)
				(xy 0.5334 -0.2794) (xy 0.5334 -0.254) (xy 0.635 -0.254) (xy 0.635 0.254) (xy 0.5334 0.254) (xy 0.5334 0.2794)
				(xy -0.508 0.2794) (xy -0.5334 0.2794)
			)
			(stroke
				(width 0)
				(type default)
			)
			(fill no)
			(layer "F.CrtYd")
		)
		(pad "1" smd rect
			(at 0.40005 0 90)
			(size 0.4572 0.508)
			(layers "F.Cu" "F.Mask" "F.Paste")
			(net "UART_T10_NODE1_RXD")
		)
		(pad "2" smd rect
			(at -0.40005 0 90)
			(size 0.4572 0.508)
			(layers "F.Cu" "F.Mask" "F.Paste")
			(net "GND")
		)
	)
	(footprint ""
		(layer "F.Cu")
		(at 68.257166 -96.709992 -90)
		(property "Reference" "R72"
			(at 54.98719 -28.370276 90)
			(unlocked yes)
			(layer "F.SilkS")
			(effects
				(font
					(size 0.7874 0.5842)
					(thickness 0.1524)
				)
				(justify left)
			)
		)
		(property "Value" ""
			(at 0 0 270)
			(layer "F.Fab")
			(effects
				(font
					(size 1.27 1.27)
				)
			)
		)
		(duplicate_pad_numbers_are_jumpers no)
		(fp_line
			(start -0.7874 0.4064)
			(end -0.7874 -0.4064)
			(stroke
				(width 0.1524)
				(type default)
			)
			(layer "F.SilkS")
		)
		(fp_line
			(start 0.7874 0.4064)
			(end -0.7874 0.4064)
			(stroke
				(width 0.1524)
				(type default)
			)
			(layer "F.SilkS")
		)
		(fp_line
			(start -0.7874 -0.4064)
			(end 0.7874 -0.4064)
			(stroke
				(width 0.1524)
				(type default)
			)
			(layer "F.SilkS")
		)
		(fp_line
			(start 0.7874 -0.4064)
			(end 0.7874 0.4064)
			(stroke
				(width 0.1524)
				(type default)
			)
			(layer "F.SilkS")
		)
		(fp_poly
			(pts
				(xy -0.508 0.2794) (xy -0.508 0.2286) (xy -0.635 0.2286) (xy -0.635 -0.254) (xy -0.5334 -0.254)
				(xy -0.5334 -0.2794) (xy 0.5334 -0.2794) (xy 0.5334 -0.254) (xy 0.635 -0.254) (xy 0.635 0.254) (xy 0.5334 0.254)
				(xy 0.5334 0.2794)
			)
			(stroke
				(width 0)
				(type default)
			)
			(fill no)
			(layer "F.CrtYd")
		)
		(pad "1" smd rect
			(at 0.40005 0 270)
			(size 0.4572 0.508)
			(layers "F.Cu" "F.Mask" "F.Paste")
			(net "LPC_CPU_NODE1_R_CLKOUT1")
		)
		(pad "2" smd rect
			(at -0.40005 0 270)
			(size 0.4572 0.508)
			(layers "F.Cu" "F.Mask" "F.Paste")
			(net "LPC_CPU_NODE1_CLKOUT1")
		)
	)
	(footprint ""
		(layer "F.Cu")
		(at 60.352686 -121.044462 -90)
		(property "Reference" "R318"
			(at 4.642612 -8.379968 90)
			(unlocked yes)
			(layer "F.SilkS")
			(effects
				(font
					(size 0.7874 0.5842)
					(thickness 0.1524)
				)
				(justify left)
			)
		)
		(property "Value" ""
			(at 0 0 270)
			(layer "F.Fab")
			(effects
				(font
					(size 1.27 1.27)
				)
			)
		)
		(duplicate_pad_numbers_are_jumpers no)
		(fp_line
			(start -0.7874 0.4064)
			(end -0.7874 -0.4064)
			(stroke
				(width 0.1524)
				(type default)
			)
			(layer "F.SilkS")
		)
		(fp_line
			(start 0.7874 0.4064)
			(end -0.7874 0.4064)
			(stroke
				(width 0.1524)
				(type default)
			)
			(layer "F.SilkS")
		)
		(fp_line
			(start -0.7874 -0.4064)
			(end 0.7874 -0.4064)
			(stroke
				(width 0.1524)
				(type default)
			)
			(layer "F.SilkS")
		)
		(fp_line
			(start 0.7874 -0.4064)
			(end 0.7874 0.4064)
			(stroke
				(width 0.1524)
				(type default)
			)
			(layer "F.SilkS")
		)
		(fp_poly
			(pts
				(xy -0.508 0.2794) (xy -0.508 0.2286) (xy -0.635 0.2286) (xy -0.635 -0.254) (xy -0.5334 -0.254)
				(xy -0.5334 -0.2794) (xy 0.5334 -0.2794) (xy 0.5334 -0.254) (xy 0.635 -0.254) (xy 0.635 0.254) (xy 0.5334 0.254)
				(xy 0.5334 0.2794)
			)
			(stroke
				(width 0)
				(type default)
			)
			(fill no)
			(layer "F.CrtYd")
		)
		(pad "1" smd rect
			(at 0.40005 0 270)
			(size 0.4572 0.508)
			(layers "F.Cu" "F.Mask" "F.Paste")
			(net "P3V3_NODE1")
		)
		(pad "2" smd rect
			(at -0.40005 0 270)
			(size 0.4572 0.508)
			(layers "F.Cu" "F.Mask" "F.Paste")
			(net "BMC_ROMA2")
		)
	)
)
